(kicad_pcb
	(version 20260206)
	(generator "pcbnew")
	(generator_version "10.0")
	(general
		(thickness 1.6)
		(legacy_teardrops no)
	)
	(paper "A4")
	(title_block
		(title "04192023_DAF0TMB3IC0_F0TG_MB_C_brd_V02_OCP.brd")
		(comment 1 "Grand Teton / footprints 5722-5730 of 8354")
	)
	(layers
		(0 "F.Cu" signal "TOP")
		(4 "In1.Cu" signal "GND")
		(6 "In2.Cu" signal "IN1")
		(8 "In3.Cu" signal "GND1")
		(10 "In4.Cu" signal "IN2")
		(12 "In5.Cu" signal "GND2")
		(14 "In6.Cu" signal "IN3")
		(16 "In7.Cu" signal "GND3")
		(18 "In8.Cu" signal "VCC")
		(20 "In9.Cu" signal "VCC1")
		(22 "In10.Cu" signal "GND4")
		(24 "In11.Cu" signal "IN4")
		(26 "In12.Cu" signal "GND5")
		(28 "In13.Cu" signal "IN5")
		(30 "In14.Cu" signal "GND6")
		(32 "In15.Cu" signal "IN6")
		(34 "In16.Cu" signal "GND7")
		(2 "B.Cu" signal "BOTTOM")
		(9 "F.Adhes" user "F.Adhesive")
		(11 "B.Adhes" user "B.Adhesive")
		(13 "F.Paste" user "Package Geometry/Pastemask Top")
		(15 "B.Paste" user "Package Geometry/Pastemask Bottom")
		(5 "F.SilkS" user "Ref Des/Silkscreen Top")
		(7 "B.SilkS" user "Ref Des/Silkscreen Bottom")
		(1 "F.Mask" user "Board Geometry/Soldermask Top")
		(3 "B.Mask" user "Board Geometry/Soldermask Bottom")
		(17 "Dwgs.User" user "User.Drawings")
		(19 "Cmts.User" user "User.Comments")
		(21 "Eco1.User" user "User.Eco1")
		(23 "Eco2.User" user "User.Eco2")
		(25 "Edge.Cuts" user "Board Geometry/Outline")
		(27 "Margin" user)
		(31 "F.CrtYd" user "Package Geometry/Place Bound Top")
		(29 "B.CrtYd" user "Package Geometry/Place Bound Bottom")
		(35 "F.Fab" user "Ref Des/Assembly Top")
		(33 "B.Fab" user "Ref Des/Assembly Bottom")
	)
	(footprint ""
		(layer "B.Cu")
		(at 113.105946 -259.845302 180)
		(property "Reference" "C2505"
			(at 0 0 0)
			(layer "B.SilkS")
			(hide yes)
			(effects
				(font
					(size 1.27 1.27)
				)
				(justify mirror)
			)
		)
		(property "Value" ""
			(at 0 0 0)
			(layer "B.Fab")
			(effects
				(font
					(size 1.27 1.27)
				)
				(justify mirror)
			)
		)
		(duplicate_pad_numbers_are_jumpers no)
		(fp_line
			(start 0.7874 0.4064)
			(end 0.7874 -0.4064)
			(stroke
				(width 0.1524)
				(type default)
			)
			(layer "B.SilkS")
		)
		(fp_line
			(start 0.7874 -0.4064)
			(end -0.7874 -0.4064)
			(stroke
				(width 0.1524)
				(type default)
			)
			(layer "B.SilkS")
		)
		(fp_line
			(start -0.7874 0.4064)
			(end 0.7874 0.4064)
			(stroke
				(width 0.1524)
				(type default)
			)
			(layer "B.SilkS")
		)
		(fp_line
			(start -0.7874 -0.4064)
			(end -0.7874 0.4064)
			(stroke
				(width 0.1524)
				(type default)
			)
			(layer "B.SilkS")
		)
		(fp_line
			(start 0.67945 0.3048)
			(end 0.67945 -0.305054)
			(stroke
				(width 0.1)
				(type default)
			)
			(layer "B.Fab")
		)
		(fp_line
			(start 0.67945 -0.305054)
			(end 0.12065 -0.305054)
			(stroke
				(width 0.1)
				(type default)
			)
			(layer "B.Fab")
		)
		(fp_line
			(start 0.12065 0.3048)
			(end 0.67945 0.3048)
			(stroke
				(width 0.1)
				(type default)
			)
			(layer "B.Fab")
		)
		(fp_line
			(start 0.12065 0.2794)
			(end 0.12065 0.3048)
			(stroke
				(width 0.1)
				(type default)
			)
			(layer "B.Fab")
		)
		(fp_line
			(start 0.12065 -0.2794)
			(end -0.12065 -0.2794)
			(stroke
				(width 0.1)
				(type default)
			)
			(layer "B.Fab")
		)
		(fp_line
			(start 0.12065 -0.305054)
			(end 0.12065 -0.2794)
			(stroke
				(width 0.1)
				(type default)
			)
			(layer "B.Fab")
		)
		(fp_line
			(start -0.120396 0.3048)
			(end -0.120396 0.2794)
			(stroke
				(width 0.1)
				(type default)
			)
			(layer "B.Fab")
		)
		(fp_line
			(start -0.120396 0.2794)
			(end 0.12065 0.2794)
			(stroke
				(width 0.1)
				(type default)
			)
			(layer "B.Fab")
		)
		(fp_line
			(start -0.12065 -0.2794)
			(end -0.12065 -0.3048)
			(stroke
				(width 0.1)
				(type default)
			)
			(layer "B.Fab")
		)
		(fp_line
			(start -0.12065 -0.3048)
			(end -0.67945 -0.3048)
			(stroke
				(width 0.1)
				(type default)
			)
			(layer "B.Fab")
		)
		(fp_line
			(start -0.67945 0.3048)
			(end -0.120396 0.3048)
			(stroke
				(width 0.1)
				(type default)
			)
			(layer "B.Fab")
		)
		(fp_line
			(start -0.67945 -0.3048)
			(end -0.67945 0.3048)
			(stroke
				(width 0.1)
				(type default)
			)
			(layer "B.Fab")
		)
		(pad "1" smd circle
			(at 0.40005 0)
			(size 0 0)
			(layers "B.Cu" "B.Mask" "B.Paste")
			(net "PVDD11_S3_P1")
		)
		(pad "2" smd circle
			(at -0.40005 0)
			(size 0 0)
			(layers "B.Cu" "B.Mask" "B.Paste")
			(net "GND")
		)
	)
	(footprint ""
		(layer "B.Cu")
		(at 117.895624 -258.405376)
		(property "Reference" "C2476"
			(at 0 0 0)
			(layer "B.SilkS")
			(hide yes)
			(effects
				(font
					(size 1.27 1.27)
				)
				(justify mirror)
			)
		)
		(property "Value" ""
			(at 0 0 0)
			(layer "B.Fab")
			(effects
				(font
					(size 1.27 1.27)
				)
				(justify mirror)
			)
		)
		(duplicate_pad_numbers_are_jumpers no)
		(fp_line
			(start -0.7874 -0.4064)
			(end -0.7874 0.4064)
			(stroke
				(width 0.1524)
				(type default)
			)
			(layer "B.SilkS")
		)
		(fp_line
			(start -0.7874 0.4064)
			(end 0.7874 0.4064)
			(stroke
				(width 0.1524)
				(type default)
			)
			(layer "B.SilkS")
		)
		(fp_line
			(start 0.7874 -0.4064)
			(end -0.7874 -0.4064)
			(stroke
				(width 0.1524)
				(type default)
			)
			(layer "B.SilkS")
		)
		(fp_line
			(start 0.7874 0.4064)
			(end 0.7874 -0.4064)
			(stroke
				(width 0.1524)
				(type default)
			)
			(layer "B.SilkS")
		)
		(fp_line
			(start -0.67945 -0.3048)
			(end -0.67945 0.3048)
			(stroke
				(width 0.1)
				(type default)
			)
			(layer "B.Fab")
		)
		(fp_line
			(start -0.67945 0.3048)
			(end -0.120396 0.3048)
			(stroke
				(width 0.1)
				(type default)
			)
			(layer "B.Fab")
		)
		(fp_line
			(start -0.12065 -0.3048)
			(end -0.67945 -0.3048)
			(stroke
				(width 0.1)
				(type default)
			)
			(layer "B.Fab")
		)
		(fp_line
			(start -0.12065 -0.2794)
			(end -0.12065 -0.3048)
			(stroke
				(width 0.1)
				(type default)
			)
			(layer "B.Fab")
		)
		(fp_line
			(start -0.120396 0.2794)
			(end 0.12065 0.2794)
			(stroke
				(width 0.1)
				(type default)
			)
			(layer "B.Fab")
		)
		(fp_line
			(start -0.120396 0.3048)
			(end -0.120396 0.2794)
			(stroke
				(width 0.1)
				(type default)
			)
			(layer "B.Fab")
		)
		(fp_line
			(start 0.12065 -0.305054)
			(end 0.12065 -0.2794)
			(stroke
				(width 0.1)
				(type default)
			)
			(layer "B.Fab")
		)
		(fp_line
			(start 0.12065 -0.2794)
			(end -0.12065 -0.2794)
			(stroke
				(width 0.1)
				(type default)
			)
			(layer "B.Fab")
		)
		(fp_line
			(start 0.12065 0.2794)
			(end 0.12065 0.3048)
			(stroke
				(width 0.1)
				(type default)
			)
			(layer "B.Fab")
		)
		(fp_line
			(start 0.12065 0.3048)
			(end 0.67945 0.3048)
			(stroke
				(width 0.1)
				(type default)
			)
			(layer "B.Fab")
		)
		(fp_line
			(start 0.67945 -0.305054)
			(end 0.12065 -0.305054)
			(stroke
				(width 0.1)
				(type default)
			)
			(layer "B.Fab")
		)
		(fp_line
			(start 0.67945 0.3048)
			(end 0.67945 -0.305054)
			(stroke
				(width 0.1)
				(type default)
			)
			(layer "B.Fab")
		)
		(pad "1" smd circle
			(at 0.40005 0 180)
			(size 0 0)
			(layers "B.Cu" "B.Mask" "B.Paste")
			(net "PVDDCR_SOC_P1")
		)
		(pad "2" smd circle
			(at -0.40005 0 180)
			(size 0 0)
			(layers "B.Cu" "B.Mask" "B.Paste")
			(net "GND")
		)
	)
	(footprint ""
		(layer "B.Cu")
		(at 351.248726 -416.899344 90)
		(property "Reference" "C6564"
			(at 0 0 90)
			(layer "B.SilkS")
			(hide yes)
			(effects
				(font
					(size 1.27 1.27)
				)
				(justify mirror)
			)
		)
		(property "Value" ""
			(at 0 0 90)
			(layer "B.Fab")
			(effects
				(font
					(size 1.27 1.27)
				)
				(justify mirror)
			)
		)
		(duplicate_pad_numbers_are_jumpers no)
		(fp_line
			(start 0.299974 -0.150114)
			(end -0.299974 -0.150114)
			(stroke
				(width 0.1)
				(type default)
			)
			(layer "B.Fab")
		)
		(fp_line
			(start -0.299974 -0.150114)
			(end -0.299974 0.150114)
			(stroke
				(width 0.1)
				(type default)
			)
			(layer "B.Fab")
		)
		(fp_line
			(start 0.299974 0.150114)
			(end 0.299974 -0.150114)
			(stroke
				(width 0.1)
				(type default)
			)
			(layer "B.Fab")
		)
		(fp_line
			(start -0.299974 0.150114)
			(end 0.299974 0.150114)
			(stroke
				(width 0.1)
				(type default)
			)
			(layer "B.Fab")
		)
		(pad "1" smd rect
			(at 0.2667 0 270)
			(size 0.3048 0.381)
			(layers "B.Cu" "B.Mask" "B.Paste")
			(net "P5E_CPU0_P1_TX_BUF_C_DN<15>")
		)
		(pad "2" smd rect
			(at -0.2667 0 270)
			(size 0.3048 0.381)
			(layers "B.Cu" "B.Mask" "B.Paste")
			(net "P5E_CPU0_P1_TX_BUF_DN<15>")
		)
	)
	(footprint ""
		(layer "B.Cu")
		(at 109.095794 -383.7432 180)
		(property "Reference" "R909"
			(at 0 0 0)
			(layer "B.SilkS")
			(hide yes)
			(effects
				(font
					(size 1.27 1.27)
				)
				(justify mirror)
			)
		)
		(property "Value" ""
			(at 0 0 0)
			(layer "B.Fab")
			(effects
				(font
					(size 1.27 1.27)
				)
				(justify mirror)
			)
		)
		(duplicate_pad_numbers_are_jumpers no)
		(fp_line
			(start 0.32512 0.175006)
			(end 0.32512 -0.175006)
			(stroke
				(width 0.1)
				(type default)
			)
			(layer "B.Fab")
		)
		(fp_line
			(start 0.32512 -0.175006)
			(end -0.32512 -0.175006)
			(stroke
				(width 0.1)
				(type default)
			)
			(layer "B.Fab")
		)
		(fp_line
			(start -0.32512 0.175006)
			(end 0.32512 0.175006)
			(stroke
				(width 0.1)
				(type default)
			)
			(layer "B.Fab")
		)
		(fp_line
			(start -0.32512 -0.175006)
			(end -0.32512 0.175006)
			(stroke
				(width 0.1)
				(type default)
			)
			(layer "B.Fab")
		)
		(pad "1" smd rect
			(at 0.2667 0)
			(size 0.3048 0.381)
			(layers "B.Cu" "B.Mask" "B.Paste")
			(net "P1V8_CPU1_RT_1D")
		)
		(pad "2" smd rect
			(at -0.2667 0 180)
			(size 0.3048 0.381)
			(layers "B.Cu" "B.Mask" "B.Paste")
			(net "RT_CPU1_P3_SCAN_MODE")
		)
	)
	(footprint ""
		(layer "B.Cu")
		(at 88.446356 -388.011162 -90)
		(property "Reference" "C202"
			(at 0 0 90)
			(layer "B.SilkS")
			(hide yes)
			(effects
				(font
					(size 1.27 1.27)
				)
				(justify mirror)
			)
		)
		(property "Value" ""
			(at 0 0 90)
			(layer "B.Fab")
			(effects
				(font
					(size 1.27 1.27)
				)
				(justify mirror)
			)
		)
		(duplicate_pad_numbers_are_jumpers no)
		(fp_line
			(start -0.299974 0.150114)
			(end 0.299974 0.150114)
			(stroke
				(width 0.1)
				(type default)
			)
			(layer "B.Fab")
		)
		(fp_line
			(start 0.299974 0.150114)
			(end 0.299974 -0.150114)
			(stroke
				(width 0.1)
				(type default)
			)
			(layer "B.Fab")
		)
		(fp_line
			(start -0.299974 -0.150114)
			(end -0.299974 0.150114)
			(stroke
				(width 0.1)
				(type default)
			)
			(layer "B.Fab")
		)
		(fp_line
			(start 0.299974 -0.150114)
			(end -0.299974 -0.150114)
			(stroke
				(width 0.1)
				(type default)
			)
			(layer "B.Fab")
		)
		(pad "1" smd rect
			(at 0.2667 0 90)
			(size 0.3048 0.381)
			(layers "B.Cu" "B.Mask" "B.Paste")
			(net "P1V8_CPU1_RT1_1A")
		)
		(pad "2" smd rect
			(at -0.2667 0 90)
			(size 0.3048 0.381)
			(layers "B.Cu" "B.Mask" "B.Paste")
			(net "GND")
		)
	)
	(footprint ""
		(layer "B.Cu")
		(at 450.088 -192.660016 180)
		(property "Reference" "C171"
			(at 0 0 0)
			(layer "B.SilkS")
			(hide yes)
			(effects
				(font
					(size 1.27 1.27)
				)
				(justify mirror)
			)
		)
		(property "Value" ""
			(at 0 0 0)
			(layer "B.Fab")
			(effects
				(font
					(size 1.27 1.27)
				)
				(justify mirror)
			)
		)
		(duplicate_pad_numbers_are_jumpers no)
		(fp_line
			(start 1.524 0.762)
			(end 1.524 -0.762)
			(stroke
				(width 0.1524)
				(type default)
			)
			(layer "B.SilkS")
		)
		(fp_line
			(start 1.524 -0.762)
			(end -1.524 -0.762)
			(stroke
				(width 0.1524)
				(type default)
			)
			(layer "B.SilkS")
		)
		(fp_line
			(start -1.524 0.762)
			(end 1.524 0.762)
			(stroke
				(width 0.1524)
				(type default)
			)
			(layer "B.SilkS")
		)
		(fp_line
			(start -1.524 -0.762)
			(end -1.524 0.762)
			(stroke
				(width 0.1524)
				(type default)
			)
			(layer "B.SilkS")
		)
		(fp_line
			(start 1.1049 0.724916)
			(end -1.1049 0.724916)
			(stroke
				(width 0.1)
				(type default)
			)
			(layer "B.Fab")
		)
		(fp_line
			(start 1.1049 -0.724916)
			(end 1.1049 0.724916)
			(stroke
				(width 0.1)
				(type default)
			)
			(layer "B.Fab")
		)
		(fp_line
			(start -1.1049 0.724916)
			(end -1.1049 -0.724916)
			(stroke
				(width 0.1)
				(type default)
			)
			(layer "B.Fab")
		)
		(fp_line
			(start -1.1049 -0.724916)
			(end 1.1049 -0.724916)
			(stroke
				(width 0.1)
				(type default)
			)
			(layer "B.Fab")
		)
		(pad "1" smd rect
			(at 0.889 0 180)
			(size 1.016 1.27)
			(layers "B.Cu" "B.Mask" "B.Paste")
			(net "P12V_MEM_CPU0")
		)
		(pad "2" smd rect
			(at -0.889 0 180)
			(size 1.016 1.27)
			(layers "B.Cu" "B.Mask" "B.Paste")
			(net "GND")
		)
	)
	(footprint ""
		(layer "B.Cu")
		(at 83.045554 -189.461648 90)
		(property "Reference" "PC277"
			(at 5.774436 -1.099566 270)
			(unlocked yes)
			(layer "B.SilkS")
			(effects
				(font
					(size 0.7874 0.5842)
					(thickness 0.1524)
				)
				(justify left mirror)
			)
		)
		(property "Value" ""
			(at 0 0 90)
			(layer "B.Fab")
			(effects
				(font
					(size 1.27 1.27)
				)
				(justify mirror)
			)
		)
		(duplicate_pad_numbers_are_jumpers no)
		(fp_line
			(start 4.533392 -2.249932)
			(end -4.533392 -2.249932)
			(stroke
				(width 0.1524)
				(type default)
			)
			(layer "B.SilkS")
		)
		(fp_line
			(start -4.533392 -2.249932)
			(end -4.533392 2.249932)
			(stroke
				(width 0.1524)
				(type default)
			)
			(layer "B.SilkS")
		)
		(fp_line
			(start 4.533392 2.249932)
			(end 4.533392 -2.249932)
			(stroke
				(width 0.1524)
				(type default)
			)
			(layer "B.SilkS")
		)
		(fp_line
			(start -4.533392 2.249932)
			(end 4.533392 2.249932)
			(stroke
				(width 0.1524)
				(type default)
			)
			(layer "B.SilkS")
		)
		(fp_rect
			(start 4.533392 -2.326132)
			(end 5.39242 2.326132)
			(stroke
				(width 0)
				(type default)
			)
			(fill yes)
			(layer "B.SilkS")
		)
		(fp_line
			(start 3.750056 -2.249932)
			(end -3.750056 -2.249932)
			(stroke
				(width 0.1)
				(type default)
			)
			(layer "B.Fab")
		)
		(fp_line
			(start -3.750056 -2.249932)
			(end -3.750056 2.249932)
			(stroke
				(width 0.1)
				(type default)
			)
			(layer "B.Fab")
		)
		(fp_line
			(start 3.750056 2.249932)
			(end 3.750056 -2.249932)
			(stroke
				(width 0.1)
				(type default)
			)
			(layer "B.Fab")
		)
		(fp_line
			(start -3.750056 2.249932)
			(end 3.750056 2.249932)
			(stroke
				(width 0.1)
				(type default)
			)
			(layer "B.Fab")
		)
		(fp_text user "-"
			(at -4.8514 -0.14605 90)
			(unlocked yes)
			(layer "B.SilkS")
			(effects
				(font
					(size 1.905 1.4224)
					(thickness 0.1524)
				)
				(justify left mirror)
			)
		)
		(fp_text user "+"
			(at 6.322314 0.786384 0)
			(unlocked yes)
			(layer "B.SilkS")
			(effects
				(font
					(size 1.905 1.4224)
					(thickness 0.1524)
				)
				(justify left mirror)
			)
		)
		(fp_text user "-"
			(at -4.8514 -0.14605 90)
			(unlocked yes)
			(layer "B.Fab")
			(effects
				(font
					(size 1.905 1.4224)
					(thickness 0.1524)
				)
				(justify left mirror)
			)
		)
		(fp_text user "+"
			(at 6.322314 0.786384 0)
			(unlocked yes)
			(layer "B.Fab")
			(effects
				(font
					(size 1.905 1.4224)
					(thickness 0.1524)
				)
				(justify left mirror)
			)
		)
		(pad "1" smd rect
			(at 3.199892 0 270)
			(size 2.413 2.8194)
			(layers "B.Cu" "B.Mask" "B.Paste")
			(net "PVDDCR_CPU0_P1")
		)
		(pad "2" smd rect
			(at -3.199892 0 270)
			(size 2.413 2.8194)
			(layers "B.Cu" "B.Mask" "B.Paste")
			(net "GND")
		)
	)
	(footprint ""
		(layer "B.Cu")
		(at 384.113278 -141.218158 180)
		(property "Reference" "PC469"
			(at 0 0 0)
			(layer "B.SilkS")
			(hide yes)
			(effects
				(font
					(size 1.27 1.27)
				)
				(justify mirror)
			)
		)
		(property "Value" ""
			(at 0 0 0)
			(layer "B.Fab")
			(effects
				(font
					(size 1.27 1.27)
				)
				(justify mirror)
			)
		)
		(duplicate_pad_numbers_are_jumpers no)
		(fp_line
			(start 0.7874 0.4064)
			(end 0.7874 -0.4064)
			(stroke
				(width 0.1524)
				(type default)
			)
			(layer "B.SilkS")
		)
		(fp_line
			(start 0.7874 -0.4064)
			(end -0.7874 -0.4064)
			(stroke
				(width 0.1524)
				(type default)
			)
			(layer "B.SilkS")
		)
		(fp_line
			(start -0.7874 0.4064)
			(end 0.7874 0.4064)
			(stroke
				(width 0.1524)
				(type default)
			)
			(layer "B.SilkS")
		)
		(fp_line
			(start -0.7874 -0.4064)
			(end -0.7874 0.4064)
			(stroke
				(width 0.1524)
				(type default)
			)
			(layer "B.SilkS")
		)
		(fp_line
			(start 0.67945 0.3048)
			(end 0.67945 -0.305054)
			(stroke
				(width 0.1)
				(type default)
			)
			(layer "B.Fab")
		)
		(fp_line
			(start 0.67945 -0.305054)
			(end 0.12065 -0.305054)
			(stroke
				(width 0.1)
				(type default)
			)
			(layer "B.Fab")
		)
		(fp_line
			(start 0.12065 0.3048)
			(end 0.67945 0.3048)
			(stroke
				(width 0.1)
				(type default)
			)
			(layer "B.Fab")
		)
		(fp_line
			(start 0.12065 0.2794)
			(end 0.12065 0.3048)
			(stroke
				(width 0.1)
				(type default)
			)
			(layer "B.Fab")
		)
		(fp_line
			(start 0.12065 -0.2794)
			(end -0.12065 -0.2794)
			(stroke
				(width 0.1)
				(type default)
			)
			(layer "B.Fab")
		)
		(fp_line
			(start 0.12065 -0.305054)
			(end 0.12065 -0.2794)
			(stroke
				(width 0.1)
				(type default)
			)
			(layer "B.Fab")
		)
		(fp_line
			(start -0.120396 0.3048)
			(end -0.120396 0.2794)
			(stroke
				(width 0.1)
				(type default)
			)
			(layer "B.Fab")
		)
		(fp_line
			(start -0.120396 0.2794)
			(end 0.12065 0.2794)
			(stroke
				(width 0.1)
				(type default)
			)
			(layer "B.Fab")
		)
		(fp_line
			(start -0.12065 -0.2794)
			(end -0.12065 -0.3048)
			(stroke
				(width 0.1)
				(type default)
			)
			(layer "B.Fab")
		)
		(fp_line
			(start -0.12065 -0.3048)
			(end -0.67945 -0.3048)
			(stroke
				(width 0.1)
				(type default)
			)
			(layer "B.Fab")
		)
		(fp_line
			(start -0.67945 0.3048)
			(end -0.120396 0.3048)
			(stroke
				(width 0.1)
				(type default)
			)
			(layer "B.Fab")
		)
		(fp_line
			(start -0.67945 -0.3048)
			(end -0.67945 0.3048)
			(stroke
				(width 0.1)
				(type default)
			)
			(layer "B.Fab")
		)
		(pad "1" smd circle
			(at 0.40005 0)
			(size 0 0)
			(layers "B.Cu" "B.Mask" "B.Paste")
			(net "PVDDCR_CPU0_P0_TEMP0")
		)
		(pad "2" smd circle
			(at -0.40005 0)
			(size 0 0)
			(layers "B.Cu" "B.Mask" "B.Paste")
			(net "GND")
		)
	)
	(footprint ""
		(layer "B.Cu")
		(at 367.101628 -423.57675 180)
		(property "Reference" "R688"
			(at 0 0 0)
			(layer "B.SilkS")
			(hide yes)
			(effects
				(font
					(size 1.27 1.27)
				)
				(justify mirror)
			)
		)
		(property "Value" ""
			(at 0 0 0)
			(layer "B.Fab")
			(effects
				(font
					(size 1.27 1.27)
				)
				(justify mirror)
			)
		)
		(duplicate_pad_numbers_are_jumpers no)
		(fp_line
			(start 0.32512 0.175006)
			(end 0.32512 -0.175006)
			(stroke
				(width 0.1)
				(type default)
			)
			(layer "B.Fab")
		)
		(fp_line
			(start 0.32512 -0.175006)
			(end -0.32512 -0.175006)
			(stroke
				(width 0.1)
				(type default)
			)
			(layer "B.Fab")
		)
		(fp_line
			(start -0.32512 0.175006)
			(end 0.32512 0.175006)
			(stroke
				(width 0.1)
				(type default)
			)
			(layer "B.Fab")
		)
		(fp_line
			(start -0.32512 -0.175006)
			(end -0.32512 0.175006)
			(stroke
				(width 0.1)
				(type default)
			)
			(layer "B.Fab")
		)
		(pad "1" smd rect
			(at 0.2667 0)
			(size 0.3048 0.381)
			(layers "B.Cu" "B.Mask" "B.Paste")
			(net "SMB_RT_CPU0_P3_ROM_R_SDA")
		)
		(pad "2" smd rect
			(at -0.2667 0 180)
			(size 0.3048 0.381)
			(layers "B.Cu" "B.Mask" "B.Paste")
			(net "SMB_RT_CPU0_P3_ROM_SDA")
		)
	)
)
